# T6G (Grand Teton) — schematic netlist excerpt (pin names and nets, part order shuffled) for the footprints in the layout excerpt that follows; sources: Cadence DE-HDL packaged netlist, KiCad conversion of 04192023_DAF0TMB3IC0_F0TG_MB_C_brd_V02_OCP.brd

R3518  Q_RES  0 5% CHIP  pkg 0402LF  page 245 : A = GPU_PEX_STRAP0 ; B = GPU_PEX_STRAP0_R
R3620  Q_RES  0 5% CHIP  pkg 0402LF  page 237 : A = INA230_3_A0 ; B = SMB_INA230_3_3V3AUX_SCL_R1

(kicad_pcb
	(version 20260206)
	(generator "pcbnew")
	(generator_version "10.0")
	(general
		(thickness 1.6)
		(legacy_teardrops no)
	)
	(paper "A4")
	(title_block
		(title "04192023_DAF0TMB3IC0_F0TG_MB_C_brd_V02_OCP.brd")
		(comment 1 "Grand Teton / footprints 3592-3593 of 8354")
	)
	(layers
		(0 "F.Cu" signal "TOP")
		(4 "In1.Cu" signal "GND")
		(6 "In2.Cu" signal "IN1")
		(8 "In3.Cu" signal "GND1")
		(10 "In4.Cu" signal "IN2")
		(12 "In5.Cu" signal "GND2")
		(14 "In6.Cu" signal "IN3")
		(16 "In7.Cu" signal "GND3")
		(18 "In8.Cu" signal "VCC")
		(20 "In9.Cu" signal "VCC1")
		(22 "In10.Cu" signal "GND4")
		(24 "In11.Cu" signal "IN4")
		(26 "In12.Cu" signal "GND5")
		(28 "In13.Cu" signal "IN5")
		(30 "In14.Cu" signal "GND6")
		(32 "In15.Cu" signal "IN6")
		(34 "In16.Cu" signal "GND7")
		(2 "B.Cu" signal "BOTTOM")
		(9 "F.Adhes" user "F.Adhesive")
		(11 "B.Adhes" user "B.Adhesive")
		(13 "F.Paste" user "Package Geometry/Pastemask Top")
		(15 "B.Paste" user "Package Geometry/Pastemask Bottom")
		(5 "F.SilkS" user "Ref Des/Silkscreen Top")
		(7 "B.SilkS" user "Ref Des/Silkscreen Bottom")
		(1 "F.Mask" user "Board Geometry/Soldermask Top")
		(3 "B.Mask" user "Board Geometry/Soldermask Bottom")
		(17 "Dwgs.User" user "User.Drawings")
		(19 "Cmts.User" user "User.Comments")
		(21 "Eco1.User" user "User.Eco1")
		(23 "Eco2.User" user "User.Eco2")
		(25 "Edge.Cuts" user "Board Geometry/Outline")
		(27 "Margin" user)
		(31 "F.CrtYd" user "Package Geometry/Place Bound Top")
		(29 "B.CrtYd" user "Package Geometry/Place Bound Bottom")
		(35 "F.Fab" user "Ref Des/Assembly Top")
		(33 "B.Fab" user "Ref Des/Assembly Bottom")
	)
	(footprint ""
		(layer "F.Cu")
		(at 68.212462 -38.405562 180)
		(property "Reference" "R3620"
			(at 0 0 180)
			(layer "F.SilkS")
			(hide yes)
			(effects
				(font
					(size 1.27 1.27)
				)
			)
		)
		(property "Value" ""
			(at 0 0 180)
			(layer "F.Fab")
			(effects
				(font
					(size 1.27 1.27)
				)
			)
		)
		(duplicate_pad_numbers_are_jumpers no)
		(fp_line
			(start 0.7874 0.4064)
			(end -0.7874 0.4064)
			(stroke
				(width 0.1524)
				(type default)
			)
			(layer "F.SilkS")
		)
		(fp_line
			(start 0.7874 -0.4064)
			(end 0.7874 0.4064)
			(stroke
				(width 0.1524)
				(type default)
			)
			(layer "F.SilkS")
		)
		(fp_line
			(start -0.7874 0.4064)
			(end -0.7874 -0.4064)
			(stroke
				(width 0.1524)
				(type default)
			)
			(layer "F.SilkS")
		)
		(fp_line
			(start -0.7874 -0.4064)
			(end 0.7874 -0.4064)
			(stroke
				(width 0.1524)
				(type default)
			)
			(layer "F.SilkS")
		)
		(fp_line
			(start 0.67945 0.3048)
			(end 0.120396 0.3048)
			(stroke
				(width 0.1)
				(type default)
			)
			(layer "F.Fab")
		)
		(fp_line
			(start 0.67945 -0.3048)
			(end 0.67945 0.3048)
			(stroke
				(width 0.1)
				(type default)
			)
			(layer "F.Fab")
		)
		(fp_line
			(start 0.12065 -0.2794)
			(end 0.12065 -0.3048)
			(stroke
				(width 0.1)
				(type default)
			)
			(layer "F.Fab")
		)
		(fp_line
			(start 0.12065 -0.3048)
			(end 0.67945 -0.3048)
			(stroke
				(width 0.1)
				(type default)
			)
			(layer "F.Fab")
		)
		(fp_line
			(start 0.120396 0.3048)
			(end 0.120396 0.2794)
			(stroke
				(width 0.1)
				(type default)
			)
			(layer "F.Fab")
		)
		(fp_line
			(start 0.120396 0.2794)
			(end -0.12065 0.2794)
			(stroke
				(width 0.1)
				(type default)
			)
			(layer "F.Fab")
		)
		(fp_line
			(start -0.12065 0.3048)
			(end -0.67945 0.3048)
			(stroke
				(width 0.1)
				(type default)
			)
			(layer "F.Fab")
		)
		(fp_line
			(start -0.12065 0.2794)
			(end -0.12065 0.3048)
			(stroke
				(width 0.1)
				(type default)
			)
			(layer "F.Fab")
		)
		(fp_line
			(start -0.12065 -0.2794)
			(end 0.12065 -0.2794)
			(stroke
				(width 0.1)
				(type default)
			)
			(layer "F.Fab")
		)
		(fp_line
			(start -0.12065 -0.305054)
			(end -0.12065 -0.2794)
			(stroke
				(width 0.1)
				(type default)
			)
			(layer "F.Fab")
		)
		(fp_line
			(start -0.67945 0.3048)
			(end -0.67945 -0.305054)
			(stroke
				(width 0.1)
				(type default)
			)
			(layer "F.Fab")
		)
		(fp_line
			(start -0.67945 -0.305054)
			(end -0.12065 -0.305054)
			(stroke
				(width 0.1)
				(type default)
			)
			(layer "F.Fab")
		)
		(pad "1" smd circle
			(at -0.40005 0 180)
			(size 0 0)
			(layers "F.Cu" "F.Mask" "F.Paste")
			(net "INA230_3_A0")
		)
		(pad "2" smd circle
			(at 0.40005 0 180)
			(size 0 0)
			(layers "F.Cu" "F.Mask" "F.Paste")
			(net "SMB_INA230_3_3V3AUX_SCL_R1")
		)
	)
	(footprint ""
		(layer "F.Cu")
		(at 185.322464 -426.405294 -90)
		(property "Reference" "R3518"
			(at 0 0 270)
			(layer "F.SilkS")
			(hide yes)
			(effects
				(font
					(size 1.27 1.27)
				)
			)
		)
		(property "Value" ""
			(at 0 0 270)
			(layer "F.Fab")
			(effects
				(font
					(size 1.27 1.27)
				)
			)
		)
		(duplicate_pad_numbers_are_jumpers no)
		(fp_line
			(start -0.7874 0.4064)
			(end -0.7874 -0.4064)
			(stroke
				(width 0.1524)
				(type default)
			)
			(layer "F.SilkS")
		)
		(fp_line
			(start 0.7874 0.4064)
			(end -0.7874 0.4064)
			(stroke
				(width 0.1524)
				(type default)
			)
			(layer "F.SilkS")
		)
		(fp_line
			(start -0.7874 -0.4064)
			(end 0.7874 -0.4064)
			(stroke
				(width 0.1524)
				(type default)
			)
			(layer "F.SilkS")
		)
		(fp_line
			(start 0.7874 -0.4064)
			(end 0.7874 0.4064)
			(stroke
				(width 0.1524)
				(type default)
			)
			(layer "F.SilkS")
		)
		(fp_line
			(start -0.67945 0.3048)
			(end -0.67945 -0.305054)
			(stroke
				(width 0.1)
				(type default)
			)
			(layer "F.Fab")
		)
		(fp_line
			(start -0.12065 0.3048)
			(end -0.67945 0.3048)
			(stroke
				(width 0.1)
				(type default)
			)
			(layer "F.Fab")
		)
		(fp_line
			(start 0.120396 0.3048)
			(end 0.120396 0.2794)
			(stroke
				(width 0.1)
				(type default)
			)
			(layer "F.Fab")
		)
		(fp_line
			(start 0.67945 0.3048)
			(end 0.120396 0.3048)
			(stroke
				(width 0.1)
				(type default)
			)
			(layer "F.Fab")
		)
		(fp_line
			(start -0.12065 0.2794)
			(end -0.12065 0.3048)
			(stroke
				(width 0.1)
				(type default)
			)
			(layer "F.Fab")
		)
		(fp_line
			(start 0.120396 0.2794)
			(end -0.12065 0.2794)
			(stroke
				(width 0.1)
				(type default)
			)
			(layer "F.Fab")
		)
		(fp_line
			(start -0.12065 -0.2794)
			(end 0.12065 -0.2794)
			(stroke
				(width 0.1)
				(type default)
			)
			(layer "F.Fab")
		)
		(fp_line
			(start 0.12065 -0.2794)
			(end 0.12065 -0.3048)
			(stroke
				(width 0.1)
				(type default)
			)
			(layer "F.Fab")
		)
		(fp_line
			(start 0.12065 -0.3048)
			(end 0.67945 -0.3048)
			(stroke
				(width 0.1)
				(type default)
			)
			(layer "F.Fab")
		)
		(fp_line
			(start 0.67945 -0.3048)
			(end 0.67945 0.3048)
			(stroke
				(width 0.1)
				(type default)
			)
			(layer "F.Fab")
		)
		(fp_line
			(start -0.67945 -0.305054)
			(end -0.12065 -0.305054)
			(stroke
				(width 0.1)
				(type default)
			)
			(layer "F.Fab")
		)
		(fp_line
			(start -0.12065 -0.305054)
			(end -0.12065 -0.2794)
			(stroke
				(width 0.1)
				(type default)
			)
			(layer "F.Fab")
		)
		(pad "1" smd circle
			(at -0.40005 0 270)
			(size 0 0)
			(layers "F.Cu" "F.Mask" "F.Paste")
			(net "GPU_PEX_STRAP0")
		)
		(pad "2" smd circle
			(at 0.40005 0 270)
			(size 0 0)
			(layers "F.Cu" "F.Mask" "F.Paste")
			(net "GPU_PEX_STRAP0_R")
		)
	)
)
